(kicad_pcb
	(version 20241229)
	(generator "pcbnew")
	(generator_version "9.0")
	(general
		(thickness 1.552)
		(legacy_teardrops no)
	)
	(paper "A4")
	(title_block
		(date "2023-07-25")
		(rev "1.1.4")
		(comment 9 "footprints 128-132 of 379")
	)
	(layers
		(0 "F.Cu" signal)
		(4 "In1.Cu" signal)
		(6 "In2.Cu" signal)
		(8 "In3.Cu" signal)
		(10 "In4.Cu" signal)
		(12 "In5.Cu" signal)
		(14 "In6.Cu" signal)
		(2 "B.Cu" signal)
		(9 "F.Adhes" user "F.Adhesive")
		(11 "B.Adhes" user "B.Adhesive")
		(13 "F.Paste" user)
		(15 "B.Paste" user)
		(5 "F.SilkS" user "F.Silkscreen")
		(7 "B.SilkS" user "B.Silkscreen")
		(1 "F.Mask" user)
		(3 "B.Mask" user)
		(17 "Dwgs.User" user "User.Drawings")
		(19 "Cmts.User" user "User.Comments")
		(21 "Eco1.User" user "User.Eco1")
		(23 "Eco2.User" user "User.Eco2")
		(25 "Edge.Cuts" user)
		(27 "Margin" user)
		(31 "F.CrtYd" user "F.Courtyard")
		(29 "B.CrtYd" user "B.Courtyard")
		(35 "F.Fab" user)
		(33 "B.Fab" user)
	)
	(footprint "antmicro-footprints:R_0402_1005Metric"
		(layer "F.Cu")
		(at 122.03 109.65 180)
		(descr "Resistor SMD 0402")
		(tags "resistor SMD 0402")
		(property "Reference" "R91"
			(at 0.95 -0.39 0)
			(layer "F.SilkS")
			(effects
				(font
					(size 0.65 0.65)
					(thickness 0.15)
				)
				(justify right bottom)
			)
		)
		(property "Value" "R_10k_0402"
			(at 0 1.4 0)
			(layer "F.Fab")
			(hide yes)
			(effects
				(font
					(size 0.7 0.7)
					(thickness 0.15)
				)
				(justify right bottom)
			)
		)
		(property "Datasheet" "https://www.bourns.com/docs/product-datasheets/cr.pdf"
			(at 0 0 180)
			(layer "F.Fab")
			(hide yes)
			(effects
				(font
					(size 1.27 1.27)
					(thickness 0.15)
				)
			)
		)
		(property "Description" "SMD Chip Resistor, 10 kohm, ± 1%, 62.5 mW, 0402 [1005 Metric], Thick Film, General Purpose"
			(at 0 0 180)
			(layer "F.Fab")
			(hide yes)
			(effects
				(font
					(size 1.27 1.27)
					(thickness 0.15)
				)
			)
		)
		(property "Author" "Antmicro"
			(at 244.06 219.3 0)
			(layer "F.Fab")
			(hide yes)
			(effects
				(font
					(size 1 1)
					(thickness 0.15)
				)
			)
		)
		(property "License" "Apache-2.0"
			(at 244.06 219.3 0)
			(layer "F.Fab")
			(hide yes)
			(effects
				(font
					(size 1 1)
					(thickness 0.15)
				)
			)
		)
		(property "MPN" "CR0402-FX-1002GLF"
			(at 244.06 219.3 0)
			(layer "F.Fab")
			(hide yes)
			(effects
				(font
					(size 1 1)
					(thickness 0.15)
				)
			)
		)
		(property "Manufacturer" "Bourns"
			(at 244.06 219.3 0)
			(layer "F.Fab")
			(hide yes)
			(effects
				(font
					(size 1 1)
					(thickness 0.15)
				)
			)
		)
		(property "Tolerance" "1%"
			(at 244.06 219.3 0)
			(layer "F.Fab")
			(hide yes)
			(effects
				(font
					(size 1 1)
					(thickness 0.15)
				)
			)
		)
		(property "Val" "10k"
			(at 244.06 219.3 0)
			(layer "F.Fab")
			(hide yes)
			(effects
				(font
					(size 1 1)
					(thickness 0.15)
				)
			)
		)
		(sheetname "/FPGA/")
		(sheetfile "fpga.kicad_sch")
		(attr smd)
		(fp_rect
			(start -0.925 -0.47)
			(end 0.925 0.47)
			(stroke
				(width 0.05)
				(type default)
			)
			(fill no)
			(layer "F.CrtYd")
		)
		(fp_rect
			(start -0.5 -0.25)
			(end 0.5 0.25)
			(stroke
				(width 0.15)
				(type solid)
			)
			(fill no)
			(layer "F.Fab")
		)
		(fp_text user "${REFERENCE}"
			(at -0.95 3.168 180)
			(layer "F.Fab")
			(effects
				(font
					(size 0.7 0.7)
					(thickness 0.15)
				)
				(justify left bottom)
			)
		)
		(fp_text user "License: Apache-2.0"
			(at -0.95 5.169 180)
			(layer "F.Fab")
			(effects
				(font
					(size 0.7 0.7)
					(thickness 0.15)
				)
				(justify left bottom)
			)
		)
		(fp_text user "Author: Antmicro"
			(at -0.95 4.169 180)
			(layer "F.Fab")
			(effects
				(font
					(size 0.7 0.7)
					(thickness 0.15)
				)
				(justify left bottom)
			)
		)
		(pad "1" smd roundrect
			(at -0.48 0 180)
			(size 0.59 0.64)
			(layers "F.Cu" "F.Mask" "F.Paste")
			(roundrect_rratio 0.25)
			(net 15 "/FPGA/INITN")
			(pintype "passive")
		)
		(pad "2" smd roundrect
			(at 0.48 0 180)
			(size 0.59 0.64)
			(layers "F.Cu" "F.Mask" "F.Paste")
			(roundrect_rratio 0.25)
			(net 2 "+3V3")
			(pintype "passive")
		)
	)
	(footprint "antmicro-footprints:TP_SMD_0.75mm"
		(layer "F.Cu")
		(at 145 92.41)
		(property "Reference" "TP46"
			(at -3.07 0.3792 0)
			(layer "F.SilkS")
			(effects
				(font
					(size 0.65 0.65)
					(thickness 0.15)
				)
				(justify left bottom)
			)
		)
		(property "Value" "TP_0.75mm_SMD"
			(at 0 1.2 0)
			(layer "F.Fab")
			(hide yes)
			(effects
				(font
					(size 0.7 0.7)
					(thickness 0.15)
				)
				(justify left bottom)
			)
		)
		(property "Description" "SMT test point"
			(at 0 0 0)
			(layer "F.Fab")
			(hide yes)
			(effects
				(font
					(size 1.27 1.27)
					(thickness 0.15)
				)
			)
		)
		(property "Author" "Antmicro"
			(at 0 0 0)
			(layer "F.Fab")
			(hide yes)
			(effects
				(font
					(size 1 1)
					(thickness 0.15)
				)
			)
		)
		(property "License" "Apache-2.0"
			(at 0 0 0)
			(layer "F.Fab")
			(hide yes)
			(effects
				(font
					(size 1 1)
					(thickness 0.15)
				)
			)
		)
		(property "MPN" ""
			(at 0 0 0)
			(layer "F.Fab")
			(hide yes)
			(effects
				(font
					(size 1 1)
					(thickness 0.15)
				)
			)
		)
		(property "Manufacturer" ""
			(at 0 0 0)
			(layer "F.Fab")
			(hide yes)
			(effects
				(font
					(size 1 1)
					(thickness 0.15)
				)
			)
		)
		(sheetname "/Peripherals/")
		(sheetfile "peripherals.kicad_sch")
		(attr exclude_from_pos_files)
		(fp_circle
			(center 0 0)
			(end 0.475 0)
			(stroke
				(width 0.05)
				(type default)
			)
			(fill no)
			(layer "F.CrtYd")
		)
		(fp_text user "${REFERENCE}"
			(at -0.4 2.7 0)
			(layer "F.Fab")
			(effects
				(font
					(size 0.7 0.7)
					(thickness 0.15)
				)
				(justify left bottom)
			)
		)
		(fp_text user "Author: Antmicro"
			(at -0.4 3.901 0)
			(layer "F.Fab")
			(effects
				(font
					(size 0.7 0.7)
					(thickness 0.15)
				)
				(justify left bottom)
			)
		)
		(fp_text user "License: Apache-2.0"
			(at -0.4 5.101 0)
			(layer "F.Fab")
			(effects
				(font
					(size 0.7 0.7)
					(thickness 0.15)
				)
				(justify left bottom)
			)
		)
		(pad "1" smd circle
			(at 0 0)
			(size 0.75 0.75)
			(layers "F.Cu" "F.Mask")
			(net 379 "Net-(U20-CBUS0)")
			(pinfunction "1")
			(pintype "passive")
		)
	)
	(footprint "antmicro-footprints:C_0402_1005Metric"
		(layer "F.Cu")
		(at 144.78 56.34)
		(descr "Capacitor SMD 0402")
		(tags "capacitor SMD 0402")
		(property "Reference" "C14"
			(at -3.15 0.3 0)
			(layer "F.SilkS")
			(effects
				(font
					(size 0.65 0.65)
					(thickness 0.15)
				)
				(justify left bottom)
			)
		)
		(property "Value" "C_100n_0402"
			(at 0 1.4 0)
			(layer "F.Fab")
			(hide yes)
			(effects
				(font
					(size 0.7 0.7)
					(thickness 0.15)
				)
				(justify left bottom)
			)
		)
		(property "Datasheet" "https://www.murata.com/products/productdetail?partno=GRM155R61H104KE14%23"
			(at 0 0 0)
			(layer "F.Fab")
			(hide yes)
			(effects
				(font
					(size 1.27 1.27)
					(thickness 0.15)
				)
			)
		)
		(property "Description" "SMD Multilayer Ceramic Capacitor, 0.1 µF, 50 V, 0402 [1005 Metric], ± 10%, X5R, GRM Series"
			(at 0 0 0)
			(layer "F.Fab")
			(hide yes)
			(effects
				(font
					(size 1.27 1.27)
					(thickness 0.15)
				)
			)
		)
		(property "Author" "Antmicro"
			(at 0 0 0)
			(layer "F.Fab")
			(hide yes)
			(effects
				(font
					(size 1 1)
					(thickness 0.15)
				)
			)
		)
		(property "Dielectric" "X5R"
			(at 0 0 0)
			(layer "F.Fab")
			(hide yes)
			(effects
				(font
					(size 1 1)
					(thickness 0.15)
				)
			)
		)
		(property "License" "Apache-2.0"
			(at 0 0 0)
			(layer "F.Fab")
			(hide yes)
			(effects
				(font
					(size 1 1)
					(thickness 0.15)
				)
			)
		)
		(property "MPN" "GRM155R61H104KE14D"
			(at 0 0 0)
			(layer "F.Fab")
			(hide yes)
			(effects
				(font
					(size 1 1)
					(thickness 0.15)
				)
			)
		)
		(property "Manufacturer" "Murata"
			(at 0 0 0)
			(layer "F.Fab")
			(hide yes)
			(effects
				(font
					(size 1 1)
					(thickness 0.15)
				)
			)
		)
		(property "Val" "100n"
			(at 0 0 0)
			(layer "F.Fab")
			(hide yes)
			(effects
				(font
					(size 1 1)
					(thickness 0.15)
				)
			)
		)
		(property "Voltage" "50V"
			(at 0 0 0)
			(layer "F.Fab")
			(hide yes)
			(effects
				(font
					(size 1 1)
					(thickness 0.15)
				)
			)
		)
		(sheetname "/Power Supply/")
		(sheetfile "supply.kicad_sch")
		(attr smd)
		(fp_rect
			(start -0.925 -0.47)
			(end 0.925 0.47)
			(stroke
				(width 0.05)
				(type default)
			)
			(fill no)
			(layer "F.CrtYd")
		)
		(fp_line
			(start -0.494 -0.25)
			(end 0.504 -0.25)
			(stroke
				(width 0.15)
				(type solid)
			)
			(layer "F.Fab")
		)
		(fp_line
			(start -0.494 0.248)
			(end -0.494 -0.25)
			(stroke
				(width 0.15)
				(type solid)
			)
			(layer "F.Fab")
		)
		(fp_line
			(start 0.504 -0.25)
			(end 0.504 0.248)
			(stroke
				(width 0.15)
				(type solid)
			)
			(layer "F.Fab")
		)
		(fp_line
			(start 0.504 0.248)
			(end -0.494 0.248)
			(stroke
				(width 0.15)
				(type solid)
			)
			(layer "F.Fab")
		)
		(fp_text user "Author: Antmicro"
			(at -0.939 3.399 0)
			(layer "F.Fab")
			(effects
				(font
					(size 0.7 0.7)
					(thickness 0.15)
				)
				(justify left bottom)
			)
		)
		(fp_text user "License: Apache-2.0"
			(at -0.939 5.799 0)
			(layer "F.Fab")
			(effects
				(font
					(size 0.7 0.7)
					(thickness 0.15)
				)
				(justify left bottom)
			)
		)
		(fp_text user "${REFERENCE}"
			(at -0.939 4.599 0)
			(layer "F.Fab")
			(effects
				(font
					(size 0.7 0.7)
					(thickness 0.15)
				)
				(justify left bottom)
			)
		)
		(pad "1" smd roundrect
			(at -0.48 0)
			(size 0.59 0.64)
			(layers "F.Cu" "F.Mask" "F.Paste")
			(roundrect_rratio 0.25)
			(net 277 "/Power Supply/1V5_SW")
			(pintype "passive")
		)
		(pad "2" smd roundrect
			(at 0.48 0)
			(size 0.59 0.64)
			(layers "F.Cu" "F.Mask" "F.Paste")
			(roundrect_rratio 0.25)
			(net 65 "Net-(U6-BST)")
			(pintype "passive")
		)
	)
	(footprint "antmicro-footprints:R_0603_1608Metric"
		(layer "F.Cu")
		(at 140.29 115.9 90)
		(descr "Resistor SMD 0603")
		(tags "resistor SMD 0603")
		(property "Reference" "R30"
			(at -3.44 0.54 90)
			(layer "F.SilkS")
			(effects
				(font
					(size 0.65 0.65)
					(thickness 0.15)
				)
				(justify left bottom)
			)
		)
		(property "Value" "R_0R_0603"
			(at 0 1.6 90)
			(layer "F.Fab")
			(hide yes)
			(effects
				(font
					(size 0.7 0.7)
					(thickness 0.15)
				)
				(justify left bottom)
			)
		)
		(property "Datasheet" "https://www.bourns.com/docs/product-datasheets/cr.pdf?sfvrsn=574d41f6_14"
			(at 0 0 90)
			(layer "F.Fab")
			(hide yes)
			(effects
				(font
					(size 1.27 1.27)
					(thickness 0.15)
				)
			)
		)
		(property "Description" "Zero Ohm Resistor, Jumper, 0603 [1608 Metric], Thick Film, 100 mW, 1 A, Surface Mount Device, CR"
			(at 0 0 90)
			(layer "F.Fab")
			(hide yes)
			(effects
				(font
					(size 1.27 1.27)
					(thickness 0.15)
				)
			)
		)
		(property "Author" "Antmicro"
			(at 256.19 -24.39 0)
			(layer "F.Fab")
			(hide yes)
			(effects
				(font
					(size 1 1)
					(thickness 0.15)
				)
			)
		)
		(property "Current" "1A"
			(at 256.19 -24.39 0)
			(layer "F.Fab")
			(hide yes)
			(effects
				(font
					(size 1 1)
					(thickness 0.15)
				)
			)
		)
		(property "License" "Apache-2.0"
			(at 256.19 -24.39 0)
			(layer "F.Fab")
			(hide yes)
			(effects
				(font
					(size 1 1)
					(thickness 0.15)
				)
			)
		)
		(property "MPN" "CR0603-J/-000ELF"
			(at 256.19 -24.39 0)
			(layer "F.Fab")
			(hide yes)
			(effects
				(font
					(size 1 1)
					(thickness 0.15)
				)
			)
		)
		(property "Manufacturer" "Bourns"
			(at 256.19 -24.39 0)
			(layer "F.Fab")
			(hide yes)
			(effects
				(font
					(size 1 1)
					(thickness 0.15)
				)
			)
		)
		(property "Tolerance" "~"
			(at 256.19 -24.39 0)
			(layer "F.Fab")
			(hide yes)
			(effects
				(font
					(size 1 1)
					(thickness 0.15)
				)
			)
		)
		(property "Val" "0R"
			(at 256.19 -24.39 0)
			(layer "F.Fab")
			(hide yes)
			(effects
				(font
					(size 1 1)
					(thickness 0.15)
				)
			)
		)
		(sheetname "/Power Supply/")
		(sheetfile "supply.kicad_sch")
		(attr smd)
		(fp_line
			(start -0.15 -0.4)
			(end 0.15 -0.4)
			(stroke
				(width 0.15)
				(type solid)
			)
			(layer "F.SilkS")
		)
		(fp_line
			(start -0.15 0.4)
			(end 0.15 0.4)
			(stroke
				(width 0.15)
				(type solid)
			)
			(layer "F.SilkS")
		)
		(fp_rect
			(start -1.25 -0.65)
			(end 1.25 0.65)
			(stroke
				(width 0.05)
				(type solid)
			)
			(fill no)
			(layer "F.CrtYd")
		)
		(fp_rect
			(start -0.8 -0.4)
			(end 0.8 0.4)
			(stroke
				(width 0.15)
				(type solid)
			)
			(fill no)
			(layer "F.Fab")
		)
		(fp_text user "Author: Antmicro"
			(at -1.25 4.9 90)
			(layer "F.Fab")
			(effects
				(font
					(size 0.7 0.7)
					(thickness 0.15)
				)
				(justify left bottom)
			)
		)
		(fp_text user "License: Apache-2.0"
			(at -1.25 5.9 90)
			(layer "F.Fab")
			(effects
				(font
					(size 0.7 0.7)
					(thickness 0.15)
				)
				(justify left bottom)
			)
		)
		(fp_text user "${REFERENCE}"
			(at -1.25 3.898 90)
			(layer "F.Fab")
			(effects
				(font
					(size 0.7 0.7)
					(thickness 0.15)
				)
				(justify left bottom)
			)
		)
		(pad "1" smd roundrect
			(at -0.7 0 90)
			(size 0.8 1)
			(layers "F.Cu" "F.Mask" "F.Paste")
			(roundrect_rratio 0.2)
			(net 279 "Net-(U9-V_{OUT})")
			(pintype "passive")
		)
		(pad "2" smd roundrect
			(at 0.7 0 90)
			(size 0.8 1)
			(layers "F.Cu" "F.Mask" "F.Paste")
			(roundrect_rratio 0.2)
			(net 3 "+1V2")
			(pintype "passive")
		)
	)
	(footprint "antmicro-footprints:R_0805_2012Metric"
		(layer "F.Cu")
		(at 134.41 57.73 90)
		(property "Reference" "R5"
			(at -0.61 1.82 90)
			(layer "F.SilkS")
			(effects
				(font
					(size 0.65 0.65)
					(thickness 0.15)
				)
				(justify left bottom)
			)
		)
		(property "Value" "R_0R_0805"
			(at 0 1.8 90)
			(layer "F.Fab")
			(hide yes)
			(effects
				(font
					(size 0.7 0.7)
					(thickness 0.15)
				)
				(justify left bottom)
			)
		)
		(property "Datasheet" "https://www.vishay.com/docs/20035/dcrcwe3.pdf"
			(at 0 0 90)
			(layer "F.Fab")
			(hide yes)
			(effects
				(font
					(size 1.27 1.27)
					(thickness 0.15)
				)
			)
		)
		(property "Description" "Zero Ohm Resistor, Jumper, 0805 [2012 Metric], Thick Film, 125 mW, 2.5 A, Surface Mount Device"
			(at 0 0 90)
			(layer "F.Fab")
			(hide yes)
			(effects
				(font
					(size 1.27 1.27)
					(thickness 0.15)
				)
			)
		)
		(property "Author" "Antmicro"
			(at 192.14 -76.68 0)
			(layer "F.Fab")
			(hide yes)
			(effects
				(font
					(size 1 1)
					(thickness 0.15)
				)
			)
		)
		(property "Current" "2.5A"
			(at 192.14 -76.68 0)
			(layer "F.Fab")
			(hide yes)
			(effects
				(font
					(size 1 1)
					(thickness 0.15)
				)
			)
		)
		(property "License" "Apache-2.0"
			(at 192.14 -76.68 0)
			(layer "F.Fab")
			(hide yes)
			(effects
				(font
					(size 1 1)
					(thickness 0.15)
				)
			)
		)
		(property "MPN" "CRCW08050000Z0EA"
			(at 192.14 -76.68 0)
			(layer "F.Fab")
			(hide yes)
			(effects
				(font
					(size 1 1)
					(thickness 0.15)
				)
			)
		)
		(property "Manufacturer" "Vishay"
			(at 192.14 -76.68 0)
			(layer "F.Fab")
			(hide yes)
			(effects
				(font
					(size 1 1)
					(thickness 0.15)
				)
			)
		)
		(property "Tolerance" "~"
			(at 192.14 -76.68 0)
			(layer "F.Fab")
			(hide yes)
			(effects
				(font
					(size 1 1)
					(thickness 0.15)
				)
			)
		)
		(property "Val" "0R"
			(at 192.14 -76.68 0)
			(layer "F.Fab")
			(hide yes)
			(effects
				(font
					(size 1 1)
					(thickness 0.15)
				)
			)
		)
		(sheetname "/Power Supply/")
		(sheetfile "supply.kicad_sch")
		(attr smd)
		(fp_line
			(start -0.3 -0.701)
			(end 0.298 -0.701)
			(stroke
				(width 0.15)
				(type solid)
			)
			(layer "F.SilkS")
		)
		(fp_line
			(start -0.32 0.699)
			(end 0.28 0.699)
			(stroke
				(width 0.15)
				(type solid)
			)
			(layer "F.SilkS")
		)
		(fp_rect
			(start 1.95 -0.9)
			(end -1.95 0.9)
			(stroke
				(width 0.05)
				(type default)
			)
			(fill no)
			(layer "F.CrtYd")
		)
		(fp_line
			(start -0.951 -0.682)
			(end 0.949 -0.682)
			(stroke
				(width 0.15)
				(type solid)
			)
			(layer "F.Fab")
		)
		(fp_line
			(start 0.949 -0.677)
			(end 0.949 0.675)
			(stroke
				(width 0.15)
				(type solid)
			)
			(layer "F.Fab")
		)
		(fp_line
			(start -0.951 -0.677)
			(end -0.951 0.675)
			(stroke
				(width 0.15)
				(type solid)
			)
			(layer "F.Fab")
		)
		(fp_line
			(start -0.951 0.68)
			(end 0.949 0.68)
			(stroke
				(width 0.15)
				(type solid)
			)
			(layer "F.Fab")
		)
		(fp_text user "${REFERENCE}"
			(at -1.9 3.1 90)
			(layer "F.Fab")
			(effects
				(font
					(size 0.7 0.7)
					(thickness 0.15)
				)
				(justify left bottom)
			)
		)
		(fp_text user "License: Apache-2.0"
			(at -1.9 5.75 90)
			(layer "F.Fab")
			(effects
				(font
					(size 0.7 0.7)
					(thickness 0.15)
				)
				(justify left bottom)
			)
		)
		(fp_text user "Author: Antmicro"
			(at -1.9 4.4 90)
			(layer "F.Fab")
			(effects
				(font
					(size 0.7 0.7)
					(thickness 0.15)
				)
				(justify left bottom)
			)
		)
		(pad "1" smd roundrect
			(at -1.1 0 90)
			(size 1.2 1.3)
			(layers "F.Cu" "F.Mask" "F.Paste")
			(roundrect_rratio 0.25)
			(net 248 "+1V5")
			(pintype "passive")
		)
		(pad "2" smd roundrect
			(at 1.1 0 90)
			(size 1.2 1.3)
			(layers "F.Cu" "F.Mask" "F.Paste")
			(roundrect_rratio 0.25)
			(net 60 "Net-(U1-DDQ)")
			(pintype "passive")
		)
	)
)
